# T6G (Grand Teton) — schematic netlist excerpt (pin names and nets, part order shuffled) for the footprints in the layout excerpt that follows; sources: Cadence DE-HDL packaged netlist, KiCad conversion of 04192023_DAF0TMB3IC0_F0TG_MB_C_brd_V02_OCP.brd

R3507  Q_RES  10K 1% CHIP  pkg 0402LF  page 130 : A = GPU_FPGA_RST_R_N ; B = GND
R2832  Q_RES  100K 1% CHIP  pkg 0402LF  page 127 : A = P3V3_AUX ; B = FM_SWB_BIC_READY_N

(kicad_pcb
	(version 20260206)
	(generator "pcbnew")
	(generator_version "10.0")
	(general
		(thickness 1.6)
		(legacy_teardrops no)
	)
	(paper "A4")
	(title_block
		(title "04192023_DAF0TMB3IC0_F0TG_MB_C_brd_V02_OCP.brd")
		(comment 1 "Grand Teton / footprints 2886-2887 of 8354")
	)
	(layers
		(0 "F.Cu" signal "TOP")
		(4 "In1.Cu" signal "GND")
		(6 "In2.Cu" signal "IN1")
		(8 "In3.Cu" signal "GND1")
		(10 "In4.Cu" signal "IN2")
		(12 "In5.Cu" signal "GND2")
		(14 "In6.Cu" signal "IN3")
		(16 "In7.Cu" signal "GND3")
		(18 "In8.Cu" signal "VCC")
		(20 "In9.Cu" signal "VCC1")
		(22 "In10.Cu" signal "GND4")
		(24 "In11.Cu" signal "IN4")
		(26 "In12.Cu" signal "GND5")
		(28 "In13.Cu" signal "IN5")
		(30 "In14.Cu" signal "GND6")
		(32 "In15.Cu" signal "IN6")
		(34 "In16.Cu" signal "GND7")
		(2 "B.Cu" signal "BOTTOM")
		(9 "F.Adhes" user "F.Adhesive")
		(11 "B.Adhes" user "B.Adhesive")
		(13 "F.Paste" user "Package Geometry/Pastemask Top")
		(15 "B.Paste" user "Package Geometry/Pastemask Bottom")
		(5 "F.SilkS" user "Ref Des/Silkscreen Top")
		(7 "B.SilkS" user "Ref Des/Silkscreen Bottom")
		(1 "F.Mask" user "Board Geometry/Soldermask Top")
		(3 "B.Mask" user "Board Geometry/Soldermask Bottom")
		(17 "Dwgs.User" user "User.Drawings")
		(19 "Cmts.User" user "User.Comments")
		(21 "Eco1.User" user "User.Eco1")
		(23 "Eco2.User" user "User.Eco2")
		(25 "Edge.Cuts" user "Board Geometry/Outline")
		(27 "Margin" user)
		(31 "F.CrtYd" user "Package Geometry/Place Bound Top")
		(29 "B.CrtYd" user "Package Geometry/Place Bound Bottom")
		(35 "F.Fab" user "Ref Des/Assembly Top")
		(33 "B.Fab" user "Ref Des/Assembly Bottom")
	)
	(footprint ""
		(layer "F.Cu")
		(at 429.136302 -436.164736 -90)
		(property "Reference" "R2832"
			(at 0 0 270)
			(layer "F.SilkS")
			(hide yes)
			(effects
				(font
					(size 1.27 1.27)
				)
			)
		)
		(property "Value" ""
			(at 0 0 270)
			(layer "F.Fab")
			(effects
				(font
					(size 1.27 1.27)
				)
			)
		)
		(duplicate_pad_numbers_are_jumpers no)
		(fp_line
			(start -0.7874 0.4064)
			(end -0.7874 -0.4064)
			(stroke
				(width 0.1524)
				(type default)
			)
			(layer "F.SilkS")
		)
		(fp_line
			(start 0.7874 0.4064)
			(end -0.7874 0.4064)
			(stroke
				(width 0.1524)
				(type default)
			)
			(layer "F.SilkS")
		)
		(fp_line
			(start -0.7874 -0.4064)
			(end 0.7874 -0.4064)
			(stroke
				(width 0.1524)
				(type default)
			)
			(layer "F.SilkS")
		)
		(fp_line
			(start 0.7874 -0.4064)
			(end 0.7874 0.4064)
			(stroke
				(width 0.1524)
				(type default)
			)
			(layer "F.SilkS")
		)
		(fp_line
			(start -0.67945 0.3048)
			(end -0.67945 -0.305054)
			(stroke
				(width 0.1)
				(type default)
			)
			(layer "F.Fab")
		)
		(fp_line
			(start -0.12065 0.3048)
			(end -0.67945 0.3048)
			(stroke
				(width 0.1)
				(type default)
			)
			(layer "F.Fab")
		)
		(fp_line
			(start 0.120396 0.3048)
			(end 0.120396 0.2794)
			(stroke
				(width 0.1)
				(type default)
			)
			(layer "F.Fab")
		)
		(fp_line
			(start 0.67945 0.3048)
			(end 0.120396 0.3048)
			(stroke
				(width 0.1)
				(type default)
			)
			(layer "F.Fab")
		)
		(fp_line
			(start -0.12065 0.2794)
			(end -0.12065 0.3048)
			(stroke
				(width 0.1)
				(type default)
			)
			(layer "F.Fab")
		)
		(fp_line
			(start 0.120396 0.2794)
			(end -0.12065 0.2794)
			(stroke
				(width 0.1)
				(type default)
			)
			(layer "F.Fab")
		)
		(fp_line
			(start -0.12065 -0.2794)
			(end 0.12065 -0.2794)
			(stroke
				(width 0.1)
				(type default)
			)
			(layer "F.Fab")
		)
		(fp_line
			(start 0.12065 -0.2794)
			(end 0.12065 -0.3048)
			(stroke
				(width 0.1)
				(type default)
			)
			(layer "F.Fab")
		)
		(fp_line
			(start 0.12065 -0.3048)
			(end 0.67945 -0.3048)
			(stroke
				(width 0.1)
				(type default)
			)
			(layer "F.Fab")
		)
		(fp_line
			(start 0.67945 -0.3048)
			(end 0.67945 0.3048)
			(stroke
				(width 0.1)
				(type default)
			)
			(layer "F.Fab")
		)
		(fp_line
			(start -0.67945 -0.305054)
			(end -0.12065 -0.305054)
			(stroke
				(width 0.1)
				(type default)
			)
			(layer "F.Fab")
		)
		(fp_line
			(start -0.12065 -0.305054)
			(end -0.12065 -0.2794)
			(stroke
				(width 0.1)
				(type default)
			)
			(layer "F.Fab")
		)
		(pad "1" smd circle
			(at -0.40005 0 270)
			(size 0 0)
			(layers "F.Cu" "F.Mask" "F.Paste")
			(net "P3V3_AUX")
		)
		(pad "2" smd circle
			(at 0.40005 0 270)
			(size 0 0)
			(layers "F.Cu" "F.Mask" "F.Paste")
			(net "FM_SWB_BIC_READY_N")
		)
	)
	(footprint ""
		(layer "F.Cu")
		(at 44.069 -434.594 180)
		(property "Reference" "R3507"
			(at 0 0 180)
			(layer "F.SilkS")
			(hide yes)
			(effects
				(font
					(size 1.27 1.27)
				)
			)
		)
		(property "Value" ""
			(at 0 0 180)
			(layer "F.Fab")
			(effects
				(font
					(size 1.27 1.27)
				)
			)
		)
		(duplicate_pad_numbers_are_jumpers no)
		(fp_line
			(start 0.7874 0.4064)
			(end -0.7874 0.4064)
			(stroke
				(width 0.1524)
				(type default)
			)
			(layer "F.SilkS")
		)
		(fp_line
			(start 0.7874 -0.4064)
			(end 0.7874 0.4064)
			(stroke
				(width 0.1524)
				(type default)
			)
			(layer "F.SilkS")
		)
		(fp_line
			(start -0.7874 0.4064)
			(end -0.7874 -0.4064)
			(stroke
				(width 0.1524)
				(type default)
			)
			(layer "F.SilkS")
		)
		(fp_line
			(start -0.7874 -0.4064)
			(end 0.7874 -0.4064)
			(stroke
				(width 0.1524)
				(type default)
			)
			(layer "F.SilkS")
		)
		(fp_line
			(start 0.67945 0.3048)
			(end 0.120396 0.3048)
			(stroke
				(width 0.1)
				(type default)
			)
			(layer "F.Fab")
		)
		(fp_line
			(start 0.67945 -0.3048)
			(end 0.67945 0.3048)
			(stroke
				(width 0.1)
				(type default)
			)
			(layer "F.Fab")
		)
		(fp_line
			(start 0.12065 -0.2794)
			(end 0.12065 -0.3048)
			(stroke
				(width 0.1)
				(type default)
			)
			(layer "F.Fab")
		)
		(fp_line
			(start 0.12065 -0.3048)
			(end 0.67945 -0.3048)
			(stroke
				(width 0.1)
				(type default)
			)
			(layer "F.Fab")
		)
		(fp_line
			(start 0.120396 0.3048)
			(end 0.120396 0.2794)
			(stroke
				(width 0.1)
				(type default)
			)
			(layer "F.Fab")
		)
		(fp_line
			(start 0.120396 0.2794)
			(end -0.12065 0.2794)
			(stroke
				(width 0.1)
				(type default)
			)
			(layer "F.Fab")
		)
		(fp_line
			(start -0.12065 0.3048)
			(end -0.67945 0.3048)
			(stroke
				(width 0.1)
				(type default)
			)
			(layer "F.Fab")
		)
		(fp_line
			(start -0.12065 0.2794)
			(end -0.12065 0.3048)
			(stroke
				(width 0.1)
				(type default)
			)
			(layer "F.Fab")
		)
		(fp_line
			(start -0.12065 -0.2794)
			(end 0.12065 -0.2794)
			(stroke
				(width 0.1)
				(type default)
			)
			(layer "F.Fab")
		)
		(fp_line
			(start -0.12065 -0.305054)
			(end -0.12065 -0.2794)
			(stroke
				(width 0.1)
				(type default)
			)
			(layer "F.Fab")
		)
		(fp_line
			(start -0.67945 0.3048)
			(end -0.67945 -0.305054)
			(stroke
				(width 0.1)
				(type default)
			)
			(layer "F.Fab")
		)
		(fp_line
			(start -0.67945 -0.305054)
			(end -0.12065 -0.305054)
			(stroke
				(width 0.1)
				(type default)
			)
			(layer "F.Fab")
		)
		(pad "1" smd circle
			(at -0.40005 0 180)
			(size 0 0)
			(layers "F.Cu" "F.Mask" "F.Paste")
			(net "GPU_FPGA_RST_R_N")
		)
		(pad "2" smd circle
			(at 0.40005 0 180)
			(size 0 0)
			(layers "F.Cu" "F.Mask" "F.Paste")
			(net "GND")
		)
	)
)
